(kicad_pcb
	(version 20260206)
	(generator "pcbnew")
	(generator_version "10.0")
	(general
		(thickness 1.6)
		(legacy_teardrops no)
	)
	(paper "A4")
	(title_block
		(title "timecard-production-celestica-r4006 — R4006-B0001-02_R01.brd")
		(comment 1 "Time Appliance Project (Time Card) / footprints 789-793 of 1113")
	)
	(layers
		(0 "F.Cu" signal "TOP")
		(4 "In1.Cu" signal "L02_GND1")
		(6 "In2.Cu" signal "L03_SIG1")
		(8 "In3.Cu" signal "L04_GND2")
		(10 "In4.Cu" signal "L05_VCC1")
		(12 "In5.Cu" signal "L06_VCC2")
		(14 "In6.Cu" signal "L07_GND3")
		(16 "In7.Cu" signal "L08_SIG2")
		(18 "In8.Cu" signal "L09_GND4")
		(2 "B.Cu" signal "BOTTOM")
		(9 "F.Adhes" user "F.Adhesive")
		(11 "B.Adhes" user "B.Adhesive")
		(13 "F.Paste" user "Package Geometry/Pastemask Top")
		(15 "B.Paste" user "Package Geometry/Pastemask Bottom")
		(5 "F.SilkS" user "Ref Des/Silkscreen Top")
		(7 "B.SilkS" user "Ref Des/Silkscreen Bottom")
		(1 "F.Mask" user "Board Geometry/Soldermask Top")
		(3 "B.Mask" user "Board Geometry/Soldermask Bottom")
		(17 "Dwgs.User" user "User.Drawings")
		(19 "Cmts.User" user "User.Comments")
		(21 "Eco1.User" user "User.Eco1")
		(23 "Eco2.User" user "User.Eco2")
		(25 "Edge.Cuts" user "Board Geometry/Outline")
		(27 "Margin" user)
		(31 "F.CrtYd" user "Package Geometry/Place Bound Top")
		(29 "B.CrtYd" user "Package Geometry/Place Bound Bottom")
		(35 "F.Fab" user "Ref Des/Assembly Top")
		(33 "B.Fab" user "Ref Des/Assembly Bottom")
	)
	(footprint ""
		(layer "B.Cu")
		(at 146.1516 -59.563 90)
		(property "Reference" "R251"
			(at 0.889 2.78003 270)
			(unlocked yes)
			(layer "B.SilkS")
			(effects
				(font
					(size 0.7874 0.5842)
					(thickness 0.1524)
				)
				(justify mirror)
			)
		)
		(property "Value" "VAL*"
			(at -0.02032 2.13233 90)
			(unlocked yes)
			(layer "B.Fab")
			(hide yes)
			(effects
				(font
					(size 0.7874 0.5842)
					(thickness 0.1524)
				)
				(justify mirror)
			)
		)
		(property "Tolerance" "TOL*"
			(at -0.044704 3.05435 90)
			(unlocked yes)
			(layer "Cmts.User")
			(hide yes)
			(effects
				(font
					(size 0.7874 0.5842)
					(thickness 0.1524)
				)
				(justify mirror)
			)
		)
		(property "User Part Number" "PARTNUM*"
			(at -0.02032 4.024884 90)
			(unlocked yes)
			(layer "Cmts.User")
			(hide yes)
			(effects
				(font
					(size 0.7874 0.5842)
					(thickness 0.1524)
				)
				(justify mirror)
			)
		)
		(property "Device Type" "RESISTOR-G155-03322-01,33.2KOHA"
			(at -0.008382 1.210564 90)
			(unlocked yes)
			(layer "B.Fab")
			(hide yes)
			(effects
				(font
					(size 0.7874 0.5842)
					(thickness 0.1524)
				)
				(justify mirror)
			)
		)
		(duplicate_pad_numbers_are_jumpers no)
		(fp_line
			(start 1.143 -0.5588)
			(end 1.143 0.5588)
			(stroke
				(width 0.1)
				(type default)
			)
			(layer "B.SilkS")
		)
		(fp_line
			(start -1.143 -0.5588)
			(end 1.143 -0.5588)
			(stroke
				(width 0.1)
				(type default)
			)
			(layer "B.SilkS")
		)
		(fp_line
			(start 1.143 0.5588)
			(end -1.143 0.5588)
			(stroke
				(width 0.1)
				(type default)
			)
			(layer "B.SilkS")
		)
		(fp_line
			(start -1.143 0.5588)
			(end -1.143 -0.5588)
			(stroke
				(width 0.1)
				(type default)
			)
			(layer "B.SilkS")
		)
		(fp_poly
			(pts
				(xy 1.143 0.5588) (xy -1.143 0.5588) (xy -1.143 -0.5588) (xy 1.143 -0.5588)
			)
			(stroke
				(width 0)
				(type default)
			)
			(fill no)
			(layer "B.CrtYd")
		)
		(fp_line
			(start 0.508 -0.3048)
			(end 0.508 0.3048)
			(stroke
				(width 0.1)
				(type default)
			)
			(layer "B.Fab")
		)
		(fp_line
			(start -0.508 -0.3048)
			(end 0.508 -0.3048)
			(stroke
				(width 0.1)
				(type default)
			)
			(layer "B.Fab")
		)
		(fp_line
			(start 0.508 0.3048)
			(end -0.508 0.3048)
			(stroke
				(width 0.1)
				(type default)
			)
			(layer "B.Fab")
		)
		(fp_line
			(start -0.508 0.3048)
			(end -0.508 -0.3048)
			(stroke
				(width 0.1)
				(type default)
			)
			(layer "B.Fab")
		)
		(pad "1" smd rect
			(at 0.5334 0 270)
			(size 0.7112 0.6096)
			(layers "B.Cu" "B.Mask" "B.Paste")
			(net "XP1R0V_AGND")
		)
		(pad "2" smd rect
			(at -0.5334 0 270)
			(size 0.7112 0.6096)
			(layers "B.Cu" "B.Mask" "B.Paste")
			(net "XP1R0V_FB_R_TO_AGND")
		)
		(zone
			(layer "B.Cu")
			(hatch none 0.5)
			(connect_pads
				(clearance 0)
			)
			(min_thickness 0.25)
			(keepout
				(tracks allowed)
				(vias not_allowed)
				(pads allowed)
				(copperpour not_allowed)
				(footprints allowed)
			)
			(placement
				(enabled no)
				(sheetname "")
			)
			(fill
				(thermal_gap 0.5)
				(thermal_bridge_width 0.5)
				(island_removal_mode 0)
			)
			(polygon
				(pts
					(xy 146.4564 -59.6392) (xy 145.8468 -59.6392) (xy 145.8468 -59.4868) (xy 146.4564 -59.4868)
				)
			)
		)
		(zone
			(layer "B.Cu")
			(hatch none 0.5)
			(connect_pads
				(clearance 0)
			)
			(min_thickness 0.25)
			(keepout
				(tracks not_allowed)
				(vias allowed)
				(pads allowed)
				(copperpour not_allowed)
				(footprints allowed)
			)
			(placement
				(enabled no)
				(sheetname "")
			)
			(fill
				(thermal_gap 0.5)
				(thermal_bridge_width 0.5)
				(island_removal_mode 0)
			)
			(polygon
				(pts
					(xy 146.4564 -59.6392) (xy 145.8468 -59.6392) (xy 145.8468 -59.4868) (xy 146.4564 -59.4868)
				)
			)
		)
	)
	(footprint ""
		(layer "B.Cu")
		(at 106.847132 -47.323248 -90)
		(property "Reference" "C221"
			(at -1.444752 -0.944118 270)
			(unlocked yes)
			(layer "B.SilkS")
			(effects
				(font
					(size 0.635 0.4064)
					(thickness 0.1524)
				)
				(justify mirror)
			)
		)
		(property "Value" "VAL*"
			(at 0 3.718306 270)
			(unlocked yes)
			(layer "B.Fab")
			(hide yes)
			(effects
				(font
					(size 0.7874 0.5842)
					(thickness 0.127)
				)
				(justify mirror)
			)
		)
		(property "Tolerance" "TOL*"
			(at 0 4.861306 270)
			(unlocked yes)
			(layer "Cmts.User")
			(hide yes)
			(effects
				(font
					(size 0.7874 0.5842)
					(thickness 0.127)
				)
				(justify mirror)
			)
		)
		(property "User Part Number" "PARTNUM*"
			(at 0 2.575306 270)
			(unlocked yes)
			(layer "Cmts.User")
			(hide yes)
			(effects
				(font
					(size 0.7874 0.5842)
					(thickness 0.127)
				)
				(justify mirror)
			)
		)
		(property "Device Type" "CAPACITOR-G105-0B104-CK,0.1UF,A"
			(at 0 1.432306 270)
			(unlocked yes)
			(layer "B.Fab")
			(hide yes)
			(effects
				(font
					(size 0.7874 0.5842)
					(thickness 0.127)
				)
				(justify mirror)
			)
		)
		(duplicate_pad_numbers_are_jumpers no)
		(fp_line
			(start -0.970026 0.4699)
			(end 0.970026 0.4699)
			(stroke
				(width 0.1)
				(type default)
			)
			(layer "B.SilkS")
		)
		(fp_line
			(start 0.970026 0.4699)
			(end 0.970026 -0.4699)
			(stroke
				(width 0.1)
				(type default)
			)
			(layer "B.SilkS")
		)
		(fp_line
			(start -0.970026 -0.4699)
			(end -0.970026 0.4699)
			(stroke
				(width 0.1)
				(type default)
			)
			(layer "B.SilkS")
		)
		(fp_line
			(start 0.970026 -0.4699)
			(end -0.970026 -0.4699)
			(stroke
				(width 0.1)
				(type default)
			)
			(layer "B.SilkS")
		)
		(fp_poly
			(pts
				(xy 0.970026 0.4699) (xy -0.970026 0.4699) (xy -0.970026 -0.4699) (xy 0.970026 -0.4699)
			)
			(stroke
				(width 0)
				(type default)
			)
			(fill no)
			(layer "B.CrtYd")
		)
		(fp_line
			(start -0.508 0.3048)
			(end 0.508 0.3048)
			(stroke
				(width 0.1)
				(type default)
			)
			(layer "B.Fab")
		)
		(fp_line
			(start 0.508 0.3048)
			(end 0.508 -0.3048)
			(stroke
				(width 0.1)
				(type default)
			)
			(layer "B.Fab")
		)
		(fp_line
			(start -0.508 -0.3048)
			(end -0.508 0.3048)
			(stroke
				(width 0.1)
				(type default)
			)
			(layer "B.Fab")
		)
		(fp_line
			(start 0.508 -0.3048)
			(end -0.508 -0.3048)
			(stroke
				(width 0.1)
				(type default)
			)
			(layer "B.Fab")
		)
		(pad "1" smd circle
			(at 0.500126 0 90)
			(size 0.635 0.635)
			(layers "B.Cu" "B.Mask" "B.Paste")
			(net "XP3R3V_FPGA")
		)
		(pad "2" smd circle
			(at -0.500126 0 90)
			(size 0.635 0.635)
			(layers "B.Cu" "B.Mask" "B.Paste")
			(net "SG")
		)
	)
	(footprint ""
		(layer "B.Cu")
		(at 8.509 -72.39 -90)
		(property "Reference" "R333"
			(at 0.381 -2.62763 270)
			(unlocked yes)
			(layer "B.SilkS")
			(effects
				(font
					(size 0.7874 0.5842)
					(thickness 0.1524)
				)
				(justify mirror)
			)
		)
		(property "Value" "VAL*"
			(at -0.02032 2.13233 270)
			(unlocked yes)
			(layer "B.Fab")
			(hide yes)
			(effects
				(font
					(size 0.7874 0.5842)
					(thickness 0.1524)
				)
				(justify mirror)
			)
		)
		(property "Tolerance" "TOL*"
			(at -0.044704 3.05435 270)
			(unlocked yes)
			(layer "Cmts.User")
			(hide yes)
			(effects
				(font
					(size 0.7874 0.5842)
					(thickness 0.1524)
				)
				(justify mirror)
			)
		)
		(property "User Part Number" "PARTNUM*"
			(at -0.02032 4.024884 270)
			(unlocked yes)
			(layer "Cmts.User")
			(hide yes)
			(effects
				(font
					(size 0.7874 0.5842)
					(thickness 0.1524)
				)
				(justify mirror)
			)
		)
		(property "Device Type" "RESISTOR-G155-14701-01,4.7KOHMA"
			(at -0.008382 1.210564 270)
			(unlocked yes)
			(layer "B.Fab")
			(hide yes)
			(effects
				(font
					(size 0.7874 0.5842)
					(thickness 0.1524)
				)
				(justify mirror)
			)
		)
		(duplicate_pad_numbers_are_jumpers no)
		(fp_line
			(start -1.143 0.5588)
			(end -1.143 -0.5588)
			(stroke
				(width 0.1)
				(type default)
			)
			(layer "B.SilkS")
		)
		(fp_line
			(start 1.143 0.5588)
			(end -1.143 0.5588)
			(stroke
				(width 0.1)
				(type default)
			)
			(layer "B.SilkS")
		)
		(fp_line
			(start -1.143 -0.5588)
			(end 1.143 -0.5588)
			(stroke
				(width 0.1)
				(type default)
			)
			(layer "B.SilkS")
		)
		(fp_line
			(start 1.143 -0.5588)
			(end 1.143 0.5588)
			(stroke
				(width 0.1)
				(type default)
			)
			(layer "B.SilkS")
		)
		(fp_rect
			(start 1.143 -0.5588)
			(end -1.143 0.5588)
			(stroke
				(width 0)
				(type default)
			)
			(fill no)
			(layer "B.CrtYd")
		)
		(fp_line
			(start -0.508 0.3048)
			(end -0.508 -0.3048)
			(stroke
				(width 0.1)
				(type default)
			)
			(layer "B.Fab")
		)
		(fp_line
			(start 0.508 0.3048)
			(end -0.508 0.3048)
			(stroke
				(width 0.1)
				(type default)
			)
			(layer "B.Fab")
		)
		(fp_line
			(start -0.508 -0.3048)
			(end 0.508 -0.3048)
			(stroke
				(width 0.1)
				(type default)
			)
			(layer "B.Fab")
		)
		(fp_line
			(start 0.508 -0.3048)
			(end 0.508 0.3048)
			(stroke
				(width 0.1)
				(type default)
			)
			(layer "B.Fab")
		)
		(pad "1" smd rect
			(at 0.5334 0 90)
			(size 0.7112 0.6096)
			(layers "B.Cu" "B.Mask" "B.Paste")
			(net "XP3R3V_FPGA")
		)
		(pad "2" smd rect
			(at -0.5334 0 90)
			(size 0.7112 0.6096)
			(layers "B.Cu" "B.Mask" "B.Paste")
			(net "UNNAMED_6_LM75BDPTSSOP8_I34_A2")
		)
		(zone
			(layer "B.Cu")
			(hatch none 0.5)
			(connect_pads
				(clearance 0)
			)
			(min_thickness 0.25)
			(keepout
				(tracks allowed)
				(vias not_allowed)
				(pads allowed)
				(copperpour not_allowed)
				(footprints allowed)
			)
			(placement
				(enabled no)
				(sheetname "")
			)
			(fill
				(thermal_gap 0.5)
				(thermal_bridge_width 0.5)
				(island_removal_mode 0)
			)
			(polygon
				(pts
					(xy 8.8138 -72.3138) (xy 8.8138 -72.4662) (xy 8.2042 -72.4662) (xy 8.2042 -72.3138)
				)
			)
		)
	)
	(footprint ""
		(layer "B.Cu")
		(at 140.97 -103.378)
		(property "Reference" "R139"
			(at -0.889 3.72237 0)
			(unlocked yes)
			(layer "B.SilkS")
			(effects
				(font
					(size 0.7874 0.5842)
					(thickness 0.1524)
				)
				(justify mirror)
			)
		)
		(property "Value" "VAL*"
			(at -0.02032 2.13233 0)
			(unlocked yes)
			(layer "B.Fab")
			(hide yes)
			(effects
				(font
					(size 0.7874 0.5842)
					(thickness 0.1524)
				)
				(justify mirror)
			)
		)
		(property "Tolerance" "TOL*"
			(at -0.044704 3.05435 0)
			(unlocked yes)
			(layer "Cmts.User")
			(hide yes)
			(effects
				(font
					(size 0.7874 0.5842)
					(thickness 0.1524)
				)
				(justify mirror)
			)
		)
		(property "User Part Number" "PARTNUM*"
			(at -0.02032 4.024884 0)
			(unlocked yes)
			(layer "Cmts.User")
			(hide yes)
			(effects
				(font
					(size 0.7874 0.5842)
					(thickness 0.1524)
				)
				(justify mirror)
			)
		)
		(property "Device Type" "RESISTOR-G155-133R0-01,33OHM,1%"
			(at -0.008382 1.210564 0)
			(unlocked yes)
			(layer "B.Fab")
			(hide yes)
			(effects
				(font
					(size 0.7874 0.5842)
					(thickness 0.1524)
				)
				(justify mirror)
			)
		)
		(duplicate_pad_numbers_are_jumpers no)
		(fp_line
			(start -1.143 -0.5588)
			(end 1.143 -0.5588)
			(stroke
				(width 0.1)
				(type default)
			)
			(layer "B.SilkS")
		)
		(fp_line
			(start -1.143 0.5588)
			(end -1.143 -0.5588)
			(stroke
				(width 0.1)
				(type default)
			)
			(layer "B.SilkS")
		)
		(fp_line
			(start 1.143 -0.5588)
			(end 1.143 0.5588)
			(stroke
				(width 0.1)
				(type default)
			)
			(layer "B.SilkS")
		)
		(fp_line
			(start 1.143 0.5588)
			(end -1.143 0.5588)
			(stroke
				(width 0.1)
				(type default)
			)
			(layer "B.SilkS")
		)
		(fp_rect
			(start -1.143 -0.5588)
			(end 1.143 0.5588)
			(stroke
				(width 0)
				(type default)
			)
			(fill no)
			(layer "B.CrtYd")
		)
		(fp_line
			(start -0.508 -0.3048)
			(end 0.508 -0.3048)
			(stroke
				(width 0.1)
				(type default)
			)
			(layer "B.Fab")
		)
		(fp_line
			(start -0.508 0.3048)
			(end -0.508 -0.3048)
			(stroke
				(width 0.1)
				(type default)
			)
			(layer "B.Fab")
		)
		(fp_line
			(start 0.508 -0.3048)
			(end 0.508 0.3048)
			(stroke
				(width 0.1)
				(type default)
			)
			(layer "B.Fab")
		)
		(fp_line
			(start 0.508 0.3048)
			(end -0.508 0.3048)
			(stroke
				(width 0.1)
				(type default)
			)
			(layer "B.Fab")
		)
		(pad "1" smd rect
			(at 0.5334 0 180)
			(size 0.7112 0.6096)
			(layers "B.Cu" "B.Mask" "B.Paste")
			(net "UNNAMED_14_RESISTOR_I58_2")
		)
		(pad "2" smd rect
			(at -0.5334 0 180)
			(size 0.7112 0.6096)
			(layers "B.Cu" "B.Mask" "B.Paste")
			(net "XP2R5V_FPGA")
		)
		(zone
			(layer "B.Cu")
			(hatch none 0.5)
			(connect_pads
				(clearance 0)
			)
			(min_thickness 0.25)
			(keepout
				(tracks allowed)
				(vias not_allowed)
				(pads allowed)
				(copperpour not_allowed)
				(footprints allowed)
			)
			(placement
				(enabled no)
				(sheetname "")
			)
			(fill
				(thermal_gap 0.5)
				(thermal_bridge_width 0.5)
				(island_removal_mode 0)
			)
			(polygon
				(pts
					(xy 140.8938 -103.6828) (xy 140.8938 -103.0732) (xy 141.0462 -103.0732) (xy 141.0462 -103.6828)
				)
			)
		)
	)
	(footprint ""
		(layer "B.Cu")
		(at 133.9342 -106.172254 -90)
		(property "Reference" "R210"
			(at 7.747254 -1.15443 270)
			(unlocked yes)
			(layer "B.SilkS")
			(effects
				(font
					(size 0.7874 0.5842)
					(thickness 0.1524)
				)
				(justify mirror)
			)
		)
		(property "Value" "VAL*"
			(at -0.02032 2.13233 270)
			(unlocked yes)
			(layer "B.Fab")
			(hide yes)
			(effects
				(font
					(size 0.7874 0.5842)
					(thickness 0.1524)
				)
				(justify mirror)
			)
		)
		(property "Device Type" "RESISTOR-G155-13300-01,330OHM,A"
			(at -0.008382 1.210564 270)
			(unlocked yes)
			(layer "B.Fab")
			(hide yes)
			(effects
				(font
					(size 0.7874 0.5842)
					(thickness 0.1524)
				)
				(justify mirror)
			)
		)
		(property "User Part Number" "PARTNUM*"
			(at -0.02032 4.024884 270)
			(unlocked yes)
			(layer "Cmts.User")
			(hide yes)
			(effects
				(font
					(size 0.7874 0.5842)
					(thickness 0.1524)
				)
				(justify mirror)
			)
		)
		(property "Tolerance" "TOL*"
			(at -0.044704 3.05435 270)
			(unlocked yes)
			(layer "Cmts.User")
			(hide yes)
			(effects
				(font
					(size 0.7874 0.5842)
					(thickness 0.1524)
				)
				(justify mirror)
			)
		)
		(duplicate_pad_numbers_are_jumpers no)
		(fp_line
			(start -1.143 0.5588)
			(end -1.143 -0.5588)
			(stroke
				(width 0.1)
				(type default)
			)
			(layer "B.SilkS")
		)
		(fp_line
			(start 1.143 0.5588)
			(end -1.143 0.5588)
			(stroke
				(width 0.1)
				(type default)
			)
			(layer "B.SilkS")
		)
		(fp_line
			(start -1.143 -0.5588)
			(end 1.143 -0.5588)
			(stroke
				(width 0.1)
				(type default)
			)
			(layer "B.SilkS")
		)
		(fp_line
			(start 1.143 -0.5588)
			(end 1.143 0.5588)
			(stroke
				(width 0.1)
				(type default)
			)
			(layer "B.SilkS")
		)
		(fp_rect
			(start 1.143 0.5588)
			(end -1.143 -0.5588)
			(stroke
				(width 0)
				(type default)
			)
			(fill no)
			(layer "B.CrtYd")
		)
		(fp_line
			(start -0.508 0.3048)
			(end -0.508 -0.3048)
			(stroke
				(width 0.1)
				(type default)
			)
			(layer "B.Fab")
		)
		(fp_line
			(start 0.508 0.3048)
			(end -0.508 0.3048)
			(stroke
				(width 0.1)
				(type default)
			)
			(layer "B.Fab")
		)
		(fp_line
			(start -0.508 -0.3048)
			(end 0.508 -0.3048)
			(stroke
				(width 0.1)
				(type default)
			)
			(layer "B.Fab")
		)
		(fp_line
			(start 0.508 -0.3048)
			(end 0.508 0.3048)
			(stroke
				(width 0.1)
				(type default)
			)
			(layer "B.Fab")
		)
		(pad "1" smd rect
			(at 0.5334 0 90)
			(size 0.7112 0.6096)
			(layers "B.Cu" "B.Mask" "B.Paste")
			(net "FPGA_DONE")
		)
		(pad "2" smd rect
			(at -0.5334 0 90)
			(size 0.7112 0.6096)
			(layers "B.Cu" "B.Mask" "B.Paste")
			(net "XP3R3V_FPGA")
		)
		(zone
			(layer "B.Cu")
			(hatch none 0.5)
			(connect_pads
				(clearance 0)
			)
			(min_thickness 0.25)
			(keepout
				(tracks allowed)
				(vias not_allowed)
				(pads allowed)
				(copperpour not_allowed)
				(footprints allowed)
			)
			(placement
				(enabled no)
				(sheetname "")
			)
			(fill
				(thermal_gap 0.5)
				(thermal_bridge_width 0.5)
				(island_removal_mode 0)
			)
			(polygon
				(pts
					(xy 133.6294 -106.096054) (xy 134.239 -106.096054) (xy 134.239 -106.248454) (xy 133.6294 -106.248454)
				)
			)
		)
	)
)
